(kicad_pcb
	(version 20260206)
	(generator "pcbnew")
	(generator_version "10.0")
	(general
		(thickness 1.6)
		(legacy_teardrops no)
	)
	(paper "A4")
	(title_block
		(title "Bryce Canyon_F.DPB_16315-1-OCP.brd")
		(comment 1 "Bryce Canyon / footprint 2079 of 2223 (IO1), pads 68-81 of 202")
	)
	(layers
		(0 "F.Cu" signal "TOP")
		(4 "In1.Cu" signal "L2GND")
		(6 "In2.Cu" signal "L3")
		(8 "In3.Cu" signal "L4GND")
		(10 "In4.Cu" signal "L5")
		(12 "In5.Cu" signal "L6VCC")
		(14 "In6.Cu" signal "L7VCC")
		(16 "In7.Cu" signal "L8")
		(18 "In8.Cu" signal "L9GND")
		(20 "In9.Cu" signal "L10")
		(22 "In10.Cu" signal "L11GND")
		(2 "B.Cu" signal "BOTTOM")
		(9 "F.Adhes" user "F.Adhesive")
		(11 "B.Adhes" user "B.Adhesive")
		(13 "F.Paste" user "Package Geometry/Pastemask Top")
		(15 "B.Paste" user "Package Geometry/Pastemask Bottom")
		(5 "F.SilkS" user "Ref Des/Silkscreen Top")
		(7 "B.SilkS" user "Ref Des/Silkscreen Bottom")
		(1 "F.Mask" user "Board Geometry/Soldermask Top")
		(3 "B.Mask" user "Board Geometry/Soldermask Bottom")
		(17 "Dwgs.User" user "User.Drawings")
		(19 "Cmts.User" user "User.Comments")
		(21 "Eco1.User" user "User.Eco1")
		(23 "Eco2.User" user "User.Eco2")
		(25 "Edge.Cuts" user "Board Geometry/Outline")
		(27 "Margin" user)
		(31 "F.CrtYd" user "Package Geometry/Place Bound Top")
		(29 "B.CrtYd" user "Package Geometry/Place Bound Bottom")
		(35 "F.Fab" user "Ref Des/Assembly Top")
		(33 "B.Fab" user "Ref Des/Assembly Bottom")
	)
	(footprint ""
		(layer "B.Cu")
		(at 143.34998 -30.550104 180)
		(property "Reference" "IO1"
			(at 0 0 0)
			(layer "B.SilkS")
			(hide yes)
			(effects
				(font
					(size 1.27 1.27)
				)
				(justify mirror)
			)
		)
		(property "Value" "DM-AMP-CONN200-13R-6-GP-01"
			(at 47.5488 -16.5862 180)
			(unlocked yes)
			(layer "B.Fab")
			(hide yes)
			(effects
				(font
					(size 1.016 1.016)
					(thickness 0.1524)
				)
				(justify mirror)
			)
		)
		(property "Device Type" "DMFIT-200P-384346H577-01"
			(at 47.5488 -18.1102 180)
			(unlocked yes)
			(layer "B.Fab")
			(hide yes)
			(effects
				(font
					(size 1.016 1.016)
					(thickness 0.1524)
				)
				(justify mirror)
			)
		)
		(duplicate_pad_numbers_are_jumpers no)
		(pad "E2" thru_hole circle
			(at 1.800098 -8.199882)
			(size 0.664718 0.664718)
			(drill 0.359918)
			(layers "*.Cu" "*.Mask")
			(remove_unused_layers no)
			(net "PCIE_IOM_A_TO_COMP_A_9_DN")
			(clearance 0.264414)
			(padstack
				(mode custom)
				(layer "In1.Cu"
					(shape circle)
					(size 0.664718 0.664718)
					(clearance 0.264414)
				)
				(layer "In2.Cu"
					(shape circle)
					(size 0.664718 0.664718)
					(clearance 0.264414)
				)
				(layer "In3.Cu"
					(shape circle)
					(size 0.664718 0.664718)
					(clearance 0.264414)
				)
				(layer "In4.Cu"
					(shape circle)
					(size 0.664718 0.664718)
					(clearance 0.264414)
				)
				(layer "In5.Cu"
					(shape circle)
					(size 0.664718 0.664718)
					(clearance 0.264414)
				)
				(layer "In6.Cu"
					(shape circle)
					(size 0.762 0.762)
					(clearance 0.1651)
				)
				(layer "In7.Cu"
					(shape circle)
					(size 0.762 0.762)
					(clearance 0.1651)
				)
				(layer "In8.Cu"
					(shape circle)
					(size 0.762 0.762)
					(clearance 0.1651)
				)
				(layer "In9.Cu"
					(shape circle)
					(size 0.762 0.762)
					(clearance 0.1651)
				)
				(layer "In10.Cu"
					(shape circle)
					(size 0.762 0.762)
					(clearance 0.1651)
				)
				(layer "B.Cu"
					(shape circle)
					(size 0.762 0.762)
					(thermal_gap 0.1651)
					(clearance 0.1651)
				)
			)
		)
		(pad "E3" thru_hole circle
			(at 3.599942 -7.199884)
			(size 0.664718 0.664718)
			(drill 0.359918)
			(layers "*.Cu" "*.Mask")
			(remove_unused_layers no)
			(net "PCIE_IOM_A_TO_COMP_A_10_DN")
			(clearance 0.264414)
			(padstack
				(mode custom)
				(layer "In1.Cu"
					(shape circle)
					(size 0.664718 0.664718)
					(clearance 0.264414)
				)
				(layer "In2.Cu"
					(shape circle)
					(size 0.664718 0.664718)
					(clearance 0.264414)
				)
				(layer "In3.Cu"
					(shape circle)
					(size 0.664718 0.664718)
					(clearance 0.264414)
				)
				(layer "In4.Cu"
					(shape circle)
					(size 0.664718 0.664718)
					(clearance 0.264414)
				)
				(layer "In5.Cu"
					(shape circle)
					(size 0.664718 0.664718)
					(clearance 0.264414)
				)
				(layer "In6.Cu"
					(shape circle)
					(size 0.762 0.762)
					(clearance 0.1651)
				)
				(layer "In7.Cu"
					(shape circle)
					(size 0.762 0.762)
					(clearance 0.1651)
				)
				(layer "In8.Cu"
					(shape circle)
					(size 0.762 0.762)
					(clearance 0.1651)
				)
				(layer "In9.Cu"
					(shape circle)
					(size 0.762 0.762)
					(clearance 0.1651)
				)
				(layer "In10.Cu"
					(shape circle)
					(size 0.762 0.762)
					(clearance 0.1651)
				)
				(layer "B.Cu"
					(shape circle)
					(size 0.762 0.762)
					(thermal_gap 0.1651)
					(clearance 0.1651)
				)
			)
		)
		(pad "E4" thru_hole circle
			(at 5.40004 -8.199882)
			(size 0.664718 0.664718)
			(drill 0.359918)
			(layers "*.Cu" "*.Mask")
			(remove_unused_layers no)
			(net "PCIE_IOM_A_TO_COMP_A_11_DN")
			(clearance 0.264414)
			(padstack
				(mode custom)
				(layer "In1.Cu"
					(shape circle)
					(size 0.664718 0.664718)
					(clearance 0.264414)
				)
				(layer "In2.Cu"
					(shape circle)
					(size 0.664718 0.664718)
					(clearance 0.264414)
				)
				(layer "In3.Cu"
					(shape circle)
					(size 0.664718 0.664718)
					(clearance 0.264414)
				)
				(layer "In4.Cu"
					(shape circle)
					(size 0.664718 0.664718)
					(clearance 0.264414)
				)
				(layer "In5.Cu"
					(shape circle)
					(size 0.664718 0.664718)
					(clearance 0.264414)
				)
				(layer "In6.Cu"
					(shape circle)
					(size 0.762 0.762)
					(clearance 0.1651)
				)
				(layer "In7.Cu"
					(shape circle)
					(size 0.762 0.762)
					(clearance 0.1651)
				)
				(layer "In8.Cu"
					(shape circle)
					(size 0.762 0.762)
					(clearance 0.1651)
				)
				(layer "In9.Cu"
					(shape circle)
					(size 0.762 0.762)
					(clearance 0.1651)
				)
				(layer "In10.Cu"
					(shape circle)
					(size 0.762 0.762)
					(clearance 0.1651)
				)
				(layer "B.Cu"
					(shape circle)
					(size 0.762 0.762)
					(thermal_gap 0.1651)
					(clearance 0.1651)
				)
			)
		)
		(pad "E5" thru_hole circle
			(at 7.199884 -7.199884)
			(size 0.664718 0.664718)
			(drill 0.359918)
			(layers "*.Cu" "*.Mask")
			(remove_unused_layers no)
			(net "PCIE_IOM_A_TO_COMP_A_12_DN")
			(clearance 0.264414)
			(padstack
				(mode custom)
				(layer "In1.Cu"
					(shape circle)
					(size 0.664718 0.664718)
					(clearance 0.264414)
				)
				(layer "In2.Cu"
					(shape circle)
					(size 0.664718 0.664718)
					(clearance 0.264414)
				)
				(layer "In3.Cu"
					(shape circle)
					(size 0.664718 0.664718)
					(clearance 0.264414)
				)
				(layer "In4.Cu"
					(shape circle)
					(size 0.664718 0.664718)
					(clearance 0.264414)
				)
				(layer "In5.Cu"
					(shape circle)
					(size 0.664718 0.664718)
					(clearance 0.264414)
				)
				(layer "In6.Cu"
					(shape circle)
					(size 0.762 0.762)
					(clearance 0.1651)
				)
				(layer "In7.Cu"
					(shape circle)
					(size 0.762 0.762)
					(clearance 0.1651)
				)
				(layer "In8.Cu"
					(shape circle)
					(size 0.762 0.762)
					(clearance 0.1651)
				)
				(layer "In9.Cu"
					(shape circle)
					(size 0.762 0.762)
					(clearance 0.1651)
				)
				(layer "In10.Cu"
					(shape circle)
					(size 0.762 0.762)
					(clearance 0.1651)
				)
				(layer "B.Cu"
					(shape circle)
					(size 0.762 0.762)
					(thermal_gap 0.1651)
					(clearance 0.1651)
				)
			)
		)
		(pad "E6" thru_hole circle
			(at 8.999982 -8.199882)
			(size 0.664718 0.664718)
			(drill 0.359918)
			(layers "*.Cu" "*.Mask")
			(remove_unused_layers no)
			(net "PCIE_IOM_A_TO_COMP_A_13_DN")
			(clearance 0.264414)
			(padstack
				(mode custom)
				(layer "In1.Cu"
					(shape circle)
					(size 0.664718 0.664718)
					(clearance 0.264414)
				)
				(layer "In2.Cu"
					(shape circle)
					(size 0.664718 0.664718)
					(clearance 0.264414)
				)
				(layer "In3.Cu"
					(shape circle)
					(size 0.664718 0.664718)
					(clearance 0.264414)
				)
				(layer "In4.Cu"
					(shape circle)
					(size 0.664718 0.664718)
					(clearance 0.264414)
				)
				(layer "In5.Cu"
					(shape circle)
					(size 0.664718 0.664718)
					(clearance 0.264414)
				)
				(layer "In6.Cu"
					(shape circle)
					(size 0.762 0.762)
					(clearance 0.1651)
				)
				(layer "In7.Cu"
					(shape circle)
					(size 0.762 0.762)
					(clearance 0.1651)
				)
				(layer "In8.Cu"
					(shape circle)
					(size 0.762 0.762)
					(clearance 0.1651)
				)
				(layer "In9.Cu"
					(shape circle)
					(size 0.762 0.762)
					(clearance 0.1651)
				)
				(layer "In10.Cu"
					(shape circle)
					(size 0.762 0.762)
					(clearance 0.1651)
				)
				(layer "B.Cu"
					(shape circle)
					(size 0.762 0.762)
					(thermal_gap 0.1651)
					(clearance 0.1651)
				)
			)
		)
		(pad "E7" thru_hole circle
			(at 10.80008 -7.199884)
			(size 0.664718 0.664718)
			(drill 0.359918)
			(layers "*.Cu" "*.Mask")
			(remove_unused_layers no)
			(net "PCIE_IOM_A_TO_COMP_A_14_DN")
			(clearance 0.264414)
			(padstack
				(mode custom)
				(layer "In1.Cu"
					(shape circle)
					(size 0.664718 0.664718)
					(clearance 0.264414)
				)
				(layer "In2.Cu"
					(shape circle)
					(size 0.664718 0.664718)
					(clearance 0.264414)
				)
				(layer "In3.Cu"
					(shape circle)
					(size 0.664718 0.664718)
					(clearance 0.264414)
				)
				(layer "In4.Cu"
					(shape circle)
					(size 0.664718 0.664718)
					(clearance 0.264414)
				)
				(layer "In5.Cu"
					(shape circle)
					(size 0.664718 0.664718)
					(clearance 0.264414)
				)
				(layer "In6.Cu"
					(shape circle)
					(size 0.762 0.762)
					(clearance 0.1651)
				)
				(layer "In7.Cu"
					(shape circle)
					(size 0.762 0.762)
					(clearance 0.1651)
				)
				(layer "In8.Cu"
					(shape circle)
					(size 0.762 0.762)
					(clearance 0.1651)
				)
				(layer "In9.Cu"
					(shape circle)
					(size 0.762 0.762)
					(clearance 0.1651)
				)
				(layer "In10.Cu"
					(shape circle)
					(size 0.762 0.762)
					(clearance 0.1651)
				)
				(layer "B.Cu"
					(shape circle)
					(size 0.762 0.762)
					(thermal_gap 0.1651)
					(clearance 0.1651)
				)
			)
		)
		(pad "E8" thru_hole circle
			(at 12.599924 -8.199882)
			(size 0.664718 0.664718)
			(drill 0.359918)
			(layers "*.Cu" "*.Mask")
			(remove_unused_layers no)
			(net "PCIE_IOM_A_TO_COMP_A_15_DN")
			(clearance 0.264414)
			(padstack
				(mode custom)
				(layer "In1.Cu"
					(shape circle)
					(size 0.664718 0.664718)
					(clearance 0.264414)
				)
				(layer "In2.Cu"
					(shape circle)
					(size 0.664718 0.664718)
					(clearance 0.264414)
				)
				(layer "In3.Cu"
					(shape circle)
					(size 0.664718 0.664718)
					(clearance 0.264414)
				)
				(layer "In4.Cu"
					(shape circle)
					(size 0.664718 0.664718)
					(clearance 0.264414)
				)
				(layer "In5.Cu"
					(shape circle)
					(size 0.664718 0.664718)
					(clearance 0.264414)
				)
				(layer "In6.Cu"
					(shape circle)
					(size 0.762 0.762)
					(clearance 0.1651)
				)
				(layer "In7.Cu"
					(shape circle)
					(size 0.762 0.762)
					(clearance 0.1651)
				)
				(layer "In8.Cu"
					(shape circle)
					(size 0.762 0.762)
					(clearance 0.1651)
				)
				(layer "In9.Cu"
					(shape circle)
					(size 0.762 0.762)
					(clearance 0.1651)
				)
				(layer "In10.Cu"
					(shape circle)
					(size 0.762 0.762)
					(clearance 0.1651)
				)
				(layer "B.Cu"
					(shape circle)
					(size 0.762 0.762)
					(thermal_gap 0.1651)
					(clearance 0.1651)
				)
			)
		)
		(pad "E9" thru_hole circle
			(at 21.599906 -7.199884)
			(size 0.664718 0.664718)
			(drill 0.359918)
			(layers "*.Cu" "*.Mask")
			(remove_unused_layers no)
			(net "PCIE_IOM_A_TO_COMP_A_16_DN")
			(clearance 0.264414)
			(padstack
				(mode custom)
				(layer "In1.Cu"
					(shape circle)
					(size 0.664718 0.664718)
					(clearance 0.264414)
				)
				(layer "In2.Cu"
					(shape circle)
					(size 0.664718 0.664718)
					(clearance 0.264414)
				)
				(layer "In3.Cu"
					(shape circle)
					(size 0.664718 0.664718)
					(clearance 0.264414)
				)
				(layer "In4.Cu"
					(shape circle)
					(size 0.664718 0.664718)
					(clearance 0.264414)
				)
				(layer "In5.Cu"
					(shape circle)
					(size 0.664718 0.664718)
					(clearance 0.264414)
				)
				(layer "In6.Cu"
					(shape circle)
					(size 0.762 0.762)
					(clearance 0.1651)
				)
				(layer "In7.Cu"
					(shape circle)
					(size 0.762 0.762)
					(clearance 0.1651)
				)
				(layer "In8.Cu"
					(shape circle)
					(size 0.762 0.762)
					(clearance 0.1651)
				)
				(layer "In9.Cu"
					(shape circle)
					(size 0.762 0.762)
					(clearance 0.1651)
				)
				(layer "In10.Cu"
					(shape circle)
					(size 0.762 0.762)
					(clearance 0.1651)
				)
				(layer "B.Cu"
					(shape circle)
					(size 0.762 0.762)
					(thermal_gap 0.1651)
					(clearance 0.1651)
				)
			)
		)
		(pad "E10" thru_hole circle
			(at 23.400004 -8.199882)
			(size 0.664718 0.664718)
			(drill 0.359918)
			(layers "*.Cu" "*.Mask")
			(remove_unused_layers no)
			(net "PCIE_IOM_A_TO_COMP_A_17_DN")
			(clearance 0.264414)
			(padstack
				(mode custom)
				(layer "In1.Cu"
					(shape circle)
					(size 0.664718 0.664718)
					(clearance 0.264414)
				)
				(layer "In2.Cu"
					(shape circle)
					(size 0.664718 0.664718)
					(clearance 0.264414)
				)
				(layer "In3.Cu"
					(shape circle)
					(size 0.664718 0.664718)
					(clearance 0.264414)
				)
				(layer "In4.Cu"
					(shape circle)
					(size 0.664718 0.664718)
					(clearance 0.264414)
				)
				(layer "In5.Cu"
					(shape circle)
					(size 0.664718 0.664718)
					(clearance 0.264414)
				)
				(layer "In6.Cu"
					(shape circle)
					(size 0.762 0.762)
					(clearance 0.1651)
				)
				(layer "In7.Cu"
					(shape circle)
					(size 0.762 0.762)
					(clearance 0.1651)
				)
				(layer "In8.Cu"
					(shape circle)
					(size 0.762 0.762)
					(clearance 0.1651)
				)
				(layer "In9.Cu"
					(shape circle)
					(size 0.762 0.762)
					(clearance 0.1651)
				)
				(layer "In10.Cu"
					(shape circle)
					(size 0.762 0.762)
					(clearance 0.1651)
				)
				(layer "B.Cu"
					(shape circle)
					(size 0.762 0.762)
					(thermal_gap 0.1651)
					(clearance 0.1651)
				)
			)
		)
		(pad "E11" thru_hole circle
			(at 25.200102 -7.199884)
			(size 0.664718 0.664718)
			(drill 0.359918)
			(layers "*.Cu" "*.Mask")
			(remove_unused_layers no)
			(net "PCIE_IOM_A_TO_COMP_A_18_DN")
			(clearance 0.264414)
			(padstack
				(mode custom)
				(layer "In1.Cu"
					(shape circle)
					(size 0.664718 0.664718)
					(clearance 0.264414)
				)
				(layer "In2.Cu"
					(shape circle)
					(size 0.664718 0.664718)
					(clearance 0.264414)
				)
				(layer "In3.Cu"
					(shape circle)
					(size 0.664718 0.664718)
					(clearance 0.264414)
				)
				(layer "In4.Cu"
					(shape circle)
					(size 0.664718 0.664718)
					(clearance 0.264414)
				)
				(layer "In5.Cu"
					(shape circle)
					(size 0.664718 0.664718)
					(clearance 0.264414)
				)
				(layer "In6.Cu"
					(shape circle)
					(size 0.762 0.762)
					(clearance 0.1651)
				)
				(layer "In7.Cu"
					(shape circle)
					(size 0.762 0.762)
					(clearance 0.1651)
				)
				(layer "In8.Cu"
					(shape circle)
					(size 0.762 0.762)
					(clearance 0.1651)
				)
				(layer "In9.Cu"
					(shape circle)
					(size 0.762 0.762)
					(clearance 0.1651)
				)
				(layer "In10.Cu"
					(shape circle)
					(size 0.762 0.762)
					(clearance 0.1651)
				)
				(layer "B.Cu"
					(shape circle)
					(size 0.762 0.762)
					(thermal_gap 0.1651)
					(clearance 0.1651)
				)
			)
		)
		(pad "E12" thru_hole circle
			(at 26.999946 -8.199882)
			(size 0.664718 0.664718)
			(drill 0.359918)
			(layers "*.Cu" "*.Mask")
			(remove_unused_layers no)
			(net "PCIE_IOM_A_TO_COMP_A_19_DN")
			(clearance 0.264414)
			(padstack
				(mode custom)
				(layer "In1.Cu"
					(shape circle)
					(size 0.664718 0.664718)
					(clearance 0.264414)
				)
				(layer "In2.Cu"
					(shape circle)
					(size 0.664718 0.664718)
					(clearance 0.264414)
				)
				(layer "In3.Cu"
					(shape circle)
					(size 0.664718 0.664718)
					(clearance 0.264414)
				)
				(layer "In4.Cu"
					(shape circle)
					(size 0.664718 0.664718)
					(clearance 0.264414)
				)
				(layer "In5.Cu"
					(shape circle)
					(size 0.664718 0.664718)
					(clearance 0.264414)
				)
				(layer "In6.Cu"
					(shape circle)
					(size 0.762 0.762)
					(clearance 0.1651)
				)
				(layer "In7.Cu"
					(shape circle)
					(size 0.762 0.762)
					(clearance 0.1651)
				)
				(layer "In8.Cu"
					(shape circle)
					(size 0.762 0.762)
					(clearance 0.1651)
				)
				(layer "In9.Cu"
					(shape circle)
					(size 0.762 0.762)
					(clearance 0.1651)
				)
				(layer "In10.Cu"
					(shape circle)
					(size 0.762 0.762)
					(clearance 0.1651)
				)
				(layer "B.Cu"
					(shape circle)
					(size 0.762 0.762)
					(thermal_gap 0.1651)
					(clearance 0.1651)
				)
			)
		)
		(pad "E13" thru_hole circle
			(at 28.800044 -7.199884)
			(size 0.664718 0.664718)
			(drill 0.359918)
			(layers "*.Cu" "*.Mask")
			(remove_unused_layers no)
			(net "PCIE_IOM_A_TO_COMP_A_20_DN")
			(clearance 0.264414)
			(padstack
				(mode custom)
				(layer "In1.Cu"
					(shape circle)
					(size 0.664718 0.664718)
					(clearance 0.264414)
				)
				(layer "In2.Cu"
					(shape circle)
					(size 0.664718 0.664718)
					(clearance 0.264414)
				)
				(layer "In3.Cu"
					(shape circle)
					(size 0.664718 0.664718)
					(clearance 0.264414)
				)
				(layer "In4.Cu"
					(shape circle)
					(size 0.664718 0.664718)
					(clearance 0.264414)
				)
				(layer "In5.Cu"
					(shape circle)
					(size 0.664718 0.664718)
					(clearance 0.264414)
				)
				(layer "In6.Cu"
					(shape circle)
					(size 0.762 0.762)
					(clearance 0.1651)
				)
				(layer "In7.Cu"
					(shape circle)
					(size 0.762 0.762)
					(clearance 0.1651)
				)
				(layer "In8.Cu"
					(shape circle)
					(size 0.762 0.762)
					(clearance 0.1651)
				)
				(layer "In9.Cu"
					(shape circle)
					(size 0.762 0.762)
					(clearance 0.1651)
				)
				(layer "In10.Cu"
					(shape circle)
					(size 0.762 0.762)
					(clearance 0.1651)
				)
				(layer "B.Cu"
					(shape circle)
					(size 0.762 0.762)
					(thermal_gap 0.1651)
					(clearance 0.1651)
				)
			)
		)
		(pad "E14" thru_hole circle
			(at 30.599888 -8.199882)
			(size 0.664718 0.664718)
			(drill 0.359918)
			(layers "*.Cu" "*.Mask")
			(remove_unused_layers no)
			(net "PCIE_IOM_A_TO_COMP_A_21_DN")
			(clearance 0.264414)
			(padstack
				(mode custom)
				(layer "In1.Cu"
					(shape circle)
					(size 0.664718 0.664718)
					(clearance 0.264414)
				)
				(layer "In2.Cu"
					(shape circle)
					(size 0.664718 0.664718)
					(clearance 0.264414)
				)
				(layer "In3.Cu"
					(shape circle)
					(size 0.664718 0.664718)
					(clearance 0.264414)
				)
				(layer "In4.Cu"
					(shape circle)
					(size 0.664718 0.664718)
					(clearance 0.264414)
				)
				(layer "In5.Cu"
					(shape circle)
					(size 0.664718 0.664718)
					(clearance 0.264414)
				)
				(layer "In6.Cu"
					(shape circle)
					(size 0.762 0.762)
					(clearance 0.1651)
				)
				(layer "In7.Cu"
					(shape circle)
					(size 0.762 0.762)
					(clearance 0.1651)
				)
				(layer "In8.Cu"
					(shape circle)
					(size 0.762 0.762)
					(clearance 0.1651)
				)
				(layer "In9.Cu"
					(shape circle)
					(size 0.762 0.762)
					(clearance 0.1651)
				)
				(layer "In10.Cu"
					(shape circle)
					(size 0.762 0.762)
					(clearance 0.1651)
				)
				(layer "B.Cu"
					(shape circle)
					(size 0.762 0.762)
					(thermal_gap 0.1651)
					(clearance 0.1651)
				)
			)
		)
		(pad "E15" thru_hole circle
			(at 32.399986 -7.199884)
			(size 0.664718 0.664718)
			(drill 0.359918)
			(layers "*.Cu" "*.Mask")
			(remove_unused_layers no)
			(net "PCIE_IOM_A_TO_COMP_A_22_DN")
			(clearance 0.264414)
			(padstack
				(mode custom)
				(layer "In1.Cu"
					(shape circle)
					(size 0.664718 0.664718)
					(clearance 0.264414)
				)
				(layer "In2.Cu"
					(shape circle)
					(size 0.664718 0.664718)
					(clearance 0.264414)
				)
				(layer "In3.Cu"
					(shape circle)
					(size 0.664718 0.664718)
					(clearance 0.264414)
				)
				(layer "In4.Cu"
					(shape circle)
					(size 0.664718 0.664718)
					(clearance 0.264414)
				)
				(layer "In5.Cu"
					(shape circle)
					(size 0.664718 0.664718)
					(clearance 0.264414)
				)
				(layer "In6.Cu"
					(shape circle)
					(size 0.762 0.762)
					(clearance 0.1651)
				)
				(layer "In7.Cu"
					(shape circle)
					(size 0.762 0.762)
					(clearance 0.1651)
				)
				(layer "In8.Cu"
					(shape circle)
					(size 0.762 0.762)
					(clearance 0.1651)
				)
				(layer "In9.Cu"
					(shape circle)
					(size 0.762 0.762)
					(clearance 0.1651)
				)
				(layer "In10.Cu"
					(shape circle)
					(size 0.762 0.762)
					(clearance 0.1651)
				)
				(layer "B.Cu"
					(shape circle)
					(size 0.762 0.762)
					(thermal_gap 0.1651)
					(clearance 0.1651)
				)
			)
		)
	)
)
